(kicad_pcb
	(version 20260206)
	(generator "pcbnew")
	(generator_version "10.0")
	(general
		(thickness 1.6)
		(legacy_teardrops no)
	)
	(paper "A4")
	(title_block
		(title "Wiwynn_Tioga_Pass_MB.brd")
		(comment 1 "Tioga Pass / footprint 4129 of 4770 (J6L1), pads 124-243 of 291")
	)
	(layers
		(0 "F.Cu" signal "TOP")
		(4 "In1.Cu" signal "L2GND")
		(6 "In2.Cu" signal "L3")
		(8 "In3.Cu" signal "L4GND")
		(10 "In4.Cu" signal "L5")
		(12 "In5.Cu" signal "L6GND")
		(14 "In6.Cu" signal "L7VCC")
		(16 "In7.Cu" signal "L8VCC")
		(18 "In8.Cu" signal "L9GND")
		(20 "In9.Cu" signal "L10")
		(22 "In10.Cu" signal "L11GND")
		(24 "In11.Cu" signal "L12")
		(26 "In12.Cu" signal "L13GND")
		(2 "B.Cu" signal "BOTTOM")
		(9 "F.Adhes" user "F.Adhesive")
		(11 "B.Adhes" user "B.Adhesive")
		(13 "F.Paste" user "Package Geometry/Pastemask Top")
		(15 "B.Paste" user "Package Geometry/Pastemask Bottom")
		(5 "F.SilkS" user "Ref Des/Silkscreen Top")
		(7 "B.SilkS" user "Ref Des/Silkscreen Bottom")
		(1 "F.Mask" user "Board Geometry/Soldermask Top")
		(3 "B.Mask" user "Board Geometry/Soldermask Bottom")
		(17 "Dwgs.User" user "User.Drawings")
		(19 "Cmts.User" user "User.Comments")
		(21 "Eco1.User" user "User.Eco1")
		(23 "Eco2.User" user "User.Eco2")
		(25 "Edge.Cuts" user "Board Geometry/Outline")
		(27 "Margin" user)
		(31 "F.CrtYd" user "Package Geometry/Place Bound Top")
		(29 "B.CrtYd" user "Package Geometry/Place Bound Bottom")
		(35 "F.Fab" user "Ref Des/Assembly Top")
		(33 "B.Fab" user "Ref Des/Assembly Bottom")
	)
	(footprint ""
		(layer "B.Cu")
		(at 194.700398 -152.078436 90)
		(property "Reference" "J6L1"
			(at 2.200148 37.96411 0)
			(unlocked yes)
			(layer "B.SilkS")
			(effects
				(font
					(size 0.7874 0.5842)
					(thickness 0.1524)
				)
				(justify left mirror)
			)
		)
		(property "Value" ""
			(at 0 0 90)
			(layer "B.Fab")
			(effects
				(font
					(size 1.27 1.27)
				)
				(justify mirror)
			)
		)
		(duplicate_pad_numbers_are_jumpers no)
		(pad "121" smd rect
			(at 0 107.100116 270)
			(size 1.8034 0.508)
			(layers "B.Cu" "B.Mask" "B.Paste")
			(net "M_F_DQS_DP<15>")
		)
		(pad "122" smd rect
			(at 0 107.95 270)
			(size 1.8034 0.508)
			(layers "B.Cu" "B.Mask" "B.Paste")
			(net "M_F_DQS_DN<15>")
		)
		(pad "123" smd rect
			(at 0 108.799884 270)
			(size 1.8034 0.508)
			(layers "B.Cu" "B.Mask" "B.Paste")
			(net "GND")
		)
		(pad "124" smd rect
			(at 0 109.650022 270)
			(size 1.8034 0.508)
			(layers "B.Cu" "B.Mask" "B.Paste")
			(net "M_F_DQ<54>")
		)
		(pad "125" smd rect
			(at 0 110.499906 270)
			(size 1.8034 0.508)
			(layers "B.Cu" "B.Mask" "B.Paste")
			(net "GND")
		)
		(pad "126" smd rect
			(at 0 111.350044 270)
			(size 1.8034 0.508)
			(layers "B.Cu" "B.Mask" "B.Paste")
			(net "M_F_DQ<50>")
		)
		(pad "127" smd rect
			(at 0 112.199928 270)
			(size 1.8034 0.508)
			(layers "B.Cu" "B.Mask" "B.Paste")
			(net "GND")
		)
		(pad "128" smd rect
			(at 0 113.050066 270)
			(size 1.8034 0.508)
			(layers "B.Cu" "B.Mask" "B.Paste")
			(net "M_F_DQ<60>")
		)
		(pad "129" smd rect
			(at 0 113.89995 270)
			(size 1.8034 0.508)
			(layers "B.Cu" "B.Mask" "B.Paste")
			(net "GND")
		)
		(pad "130" smd rect
			(at 0 114.750088 270)
			(size 1.8034 0.508)
			(layers "B.Cu" "B.Mask" "B.Paste")
			(net "M_F_DQ<56>")
		)
		(pad "131" smd rect
			(at 0 115.599972 270)
			(size 1.8034 0.508)
			(layers "B.Cu" "B.Mask" "B.Paste")
			(net "GND")
		)
		(pad "132" smd rect
			(at 0 116.45011 270)
			(size 1.8034 0.508)
			(layers "B.Cu" "B.Mask" "B.Paste")
			(net "M_F_DQS_DP<16>")
		)
		(pad "133" smd rect
			(at 0 117.299994 270)
			(size 1.8034 0.508)
			(layers "B.Cu" "B.Mask" "B.Paste")
			(net "M_F_DQS_DN<16>")
		)
		(pad "134" smd rect
			(at 0 118.149878 270)
			(size 1.8034 0.508)
			(layers "B.Cu" "B.Mask" "B.Paste")
			(net "GND")
		)
		(pad "135" smd rect
			(at 0 119.000016 270)
			(size 1.8034 0.508)
			(layers "B.Cu" "B.Mask" "B.Paste")
			(net "M_F_DQ<62>")
		)
		(pad "136" smd rect
			(at 0 119.8499 270)
			(size 1.8034 0.508)
			(layers "B.Cu" "B.Mask" "B.Paste")
			(net "GND")
		)
		(pad "137" smd rect
			(at 0 120.700038 270)
			(size 1.8034 0.508)
			(layers "B.Cu" "B.Mask" "B.Paste")
			(net "M_F_DQ<58>")
		)
		(pad "138" smd rect
			(at 0 121.549922 270)
			(size 1.8034 0.508)
			(layers "B.Cu" "B.Mask" "B.Paste")
			(net "GND")
		)
		(pad "139" smd rect
			(at 0 122.40006 270)
			(size 1.8034 0.508)
			(layers "B.Cu" "B.Mask" "B.Paste")
			(net "PVPP_DEF")
		)
		(pad "140" smd rect
			(at 0 123.249944 270)
			(size 1.8034 0.508)
			(layers "B.Cu" "B.Mask" "B.Paste")
			(net "GND")
		)
		(pad "141" smd rect
			(at 0 124.100082 270)
			(size 1.8034 0.508)
			(layers "B.Cu" "B.Mask" "B.Paste")
			(net "SMB_DDR_DEF_VPP_SCL")
		)
		(pad "142" smd rect
			(at 0 124.949966 270)
			(size 1.8034 0.508)
			(layers "B.Cu" "B.Mask" "B.Paste")
			(net "PVPP_DEF")
		)
		(pad "143" smd rect
			(at 0 125.800104 270)
			(size 1.8034 0.508)
			(layers "B.Cu" "B.Mask" "B.Paste")
			(net "PVPP_DEF")
		)
		(pad "144" smd rect
			(at 0 126.649988 270)
			(size 1.8034 0.508)
			(layers "B.Cu" "B.Mask" "B.Paste")
			(net "TP_CH_F_DIMM_F1_RFU_2")
		)
		(pad "145" smd rect
			(at -4.59994 0 270)
			(size 1.8034 0.508)
			(layers "B.Cu" "B.Mask" "B.Paste")
			(net "P12V_NVDIMM_DEF")
		)
		(pad "146" smd rect
			(at -4.59994 0.849884 270)
			(size 1.8034 0.508)
			(layers "B.Cu" "B.Mask" "B.Paste")
			(net "M_F_VREF")
		)
		(pad "147" smd rect
			(at -4.59994 1.700022 270)
			(size 1.8034 0.508)
			(layers "B.Cu" "B.Mask" "B.Paste")
			(net "GND")
		)
		(pad "148" smd rect
			(at -4.59994 2.549906 270)
			(size 1.8034 0.508)
			(layers "B.Cu" "B.Mask" "B.Paste")
			(net "M_F_DQ<5>")
		)
		(pad "149" smd rect
			(at -4.59994 3.400044 270)
			(size 1.8034 0.508)
			(layers "B.Cu" "B.Mask" "B.Paste")
			(net "GND")
		)
		(pad "150" smd rect
			(at -4.59994 4.249928 270)
			(size 1.8034 0.508)
			(layers "B.Cu" "B.Mask" "B.Paste")
			(net "M_F_DQ<1>")
		)
		(pad "151" smd rect
			(at -4.59994 5.100066 270)
			(size 1.8034 0.508)
			(layers "B.Cu" "B.Mask" "B.Paste")
			(net "GND")
		)
		(pad "152" smd rect
			(at -4.59994 5.94995 270)
			(size 1.8034 0.508)
			(layers "B.Cu" "B.Mask" "B.Paste")
			(net "M_F_DQS_DN<0>")
		)
		(pad "153" smd rect
			(at -4.59994 6.800088 270)
			(size 1.8034 0.508)
			(layers "B.Cu" "B.Mask" "B.Paste")
			(net "M_F_DQS_DP<0>")
		)
		(pad "154" smd rect
			(at -4.59994 7.649972 270)
			(size 1.8034 0.508)
			(layers "B.Cu" "B.Mask" "B.Paste")
			(net "GND")
		)
		(pad "155" smd rect
			(at -4.59994 8.50011 270)
			(size 1.8034 0.508)
			(layers "B.Cu" "B.Mask" "B.Paste")
			(net "M_F_DQ<7>")
		)
		(pad "156" smd rect
			(at -4.59994 9.349994 270)
			(size 1.8034 0.508)
			(layers "B.Cu" "B.Mask" "B.Paste")
			(net "GND")
		)
		(pad "157" smd rect
			(at -4.59994 10.199878 270)
			(size 1.8034 0.508)
			(layers "B.Cu" "B.Mask" "B.Paste")
			(net "M_F_DQ<3>")
		)
		(pad "158" smd rect
			(at -4.59994 11.050016 270)
			(size 1.8034 0.508)
			(layers "B.Cu" "B.Mask" "B.Paste")
			(net "GND")
		)
		(pad "159" smd rect
			(at -4.59994 11.8999 270)
			(size 1.8034 0.508)
			(layers "B.Cu" "B.Mask" "B.Paste")
			(net "M_F_DQ<13>")
		)
		(pad "160" smd rect
			(at -4.59994 12.750038 270)
			(size 1.8034 0.508)
			(layers "B.Cu" "B.Mask" "B.Paste")
			(net "GND")
		)
		(pad "161" smd rect
			(at -4.59994 13.599922 270)
			(size 1.8034 0.508)
			(layers "B.Cu" "B.Mask" "B.Paste")
			(net "M_F_DQ<9>")
		)
		(pad "162" smd rect
			(at -4.59994 14.45006 270)
			(size 1.8034 0.508)
			(layers "B.Cu" "B.Mask" "B.Paste")
			(net "GND")
		)
		(pad "163" smd rect
			(at -4.59994 15.299944 270)
			(size 1.8034 0.508)
			(layers "B.Cu" "B.Mask" "B.Paste")
			(net "M_F_DQS_DN<1>")
		)
		(pad "164" smd rect
			(at -4.59994 16.150082 270)
			(size 1.8034 0.508)
			(layers "B.Cu" "B.Mask" "B.Paste")
			(net "M_F_DQS_DP<1>")
		)
		(pad "165" smd rect
			(at -4.59994 16.999966 270)
			(size 1.8034 0.508)
			(layers "B.Cu" "B.Mask" "B.Paste")
			(net "GND")
		)
		(pad "166" smd rect
			(at -4.59994 17.850104 270)
			(size 1.8034 0.508)
			(layers "B.Cu" "B.Mask" "B.Paste")
			(net "M_F_DQ<15>")
		)
		(pad "167" smd rect
			(at -4.59994 18.699988 270)
			(size 1.8034 0.508)
			(layers "B.Cu" "B.Mask" "B.Paste")
			(net "GND")
		)
		(pad "168" smd rect
			(at -4.59994 19.550126 270)
			(size 1.8034 0.508)
			(layers "B.Cu" "B.Mask" "B.Paste")
			(net "M_F_DQ<11>")
		)
		(pad "169" smd rect
			(at -4.59994 20.40001 270)
			(size 1.8034 0.508)
			(layers "B.Cu" "B.Mask" "B.Paste")
			(net "GND")
		)
		(pad "170" smd rect
			(at -4.59994 21.249894 270)
			(size 1.8034 0.508)
			(layers "B.Cu" "B.Mask" "B.Paste")
			(net "M_F_DQ<21>")
		)
		(pad "171" smd rect
			(at -4.59994 22.100032 270)
			(size 1.8034 0.508)
			(layers "B.Cu" "B.Mask" "B.Paste")
			(net "GND")
		)
		(pad "172" smd rect
			(at -4.59994 22.949916 270)
			(size 1.8034 0.508)
			(layers "B.Cu" "B.Mask" "B.Paste")
			(net "M_F_DQ<17>")
		)
		(pad "173" smd rect
			(at -4.59994 23.800054 270)
			(size 1.8034 0.508)
			(layers "B.Cu" "B.Mask" "B.Paste")
			(net "GND")
		)
		(pad "174" smd rect
			(at -4.59994 24.649938 270)
			(size 1.8034 0.508)
			(layers "B.Cu" "B.Mask" "B.Paste")
			(net "M_F_DQS_DN<2>")
		)
		(pad "175" smd rect
			(at -4.59994 25.500076 270)
			(size 1.8034 0.508)
			(layers "B.Cu" "B.Mask" "B.Paste")
			(net "M_F_DQS_DP<2>")
		)
		(pad "176" smd rect
			(at -4.59994 26.34996 270)
			(size 1.8034 0.508)
			(layers "B.Cu" "B.Mask" "B.Paste")
			(net "GND")
		)
		(pad "177" smd rect
			(at -4.59994 27.200098 270)
			(size 1.8034 0.508)
			(layers "B.Cu" "B.Mask" "B.Paste")
			(net "M_F_DQ<23>")
		)
		(pad "178" smd rect
			(at -4.59994 28.049982 270)
			(size 1.8034 0.508)
			(layers "B.Cu" "B.Mask" "B.Paste")
			(net "GND")
		)
		(pad "179" smd rect
			(at -4.59994 28.90012 270)
			(size 1.8034 0.508)
			(layers "B.Cu" "B.Mask" "B.Paste")
			(net "M_F_DQ<19>")
		)
		(pad "180" smd rect
			(at -4.59994 29.750004 270)
			(size 1.8034 0.508)
			(layers "B.Cu" "B.Mask" "B.Paste")
			(net "GND")
		)
		(pad "181" smd rect
			(at -4.59994 30.599888 270)
			(size 1.8034 0.508)
			(layers "B.Cu" "B.Mask" "B.Paste")
			(net "M_F_DQ<29>")
		)
		(pad "182" smd rect
			(at -4.59994 31.450026 270)
			(size 1.8034 0.508)
			(layers "B.Cu" "B.Mask" "B.Paste")
			(net "GND")
		)
		(pad "183" smd rect
			(at -4.59994 32.29991 270)
			(size 1.8034 0.508)
			(layers "B.Cu" "B.Mask" "B.Paste")
			(net "M_F_DQ<25>")
		)
		(pad "184" smd rect
			(at -4.59994 33.150048 270)
			(size 1.8034 0.508)
			(layers "B.Cu" "B.Mask" "B.Paste")
			(net "GND")
		)
		(pad "185" smd rect
			(at -4.59994 33.999932 270)
			(size 1.8034 0.508)
			(layers "B.Cu" "B.Mask" "B.Paste")
			(net "M_F_DQS_DN<3>")
		)
		(pad "186" smd rect
			(at -4.59994 34.85007 270)
			(size 1.8034 0.508)
			(layers "B.Cu" "B.Mask" "B.Paste")
			(net "M_F_DQS_DP<3>")
		)
		(pad "187" smd rect
			(at -4.59994 35.699954 270)
			(size 1.8034 0.508)
			(layers "B.Cu" "B.Mask" "B.Paste")
			(net "GND")
		)
		(pad "188" smd rect
			(at -4.59994 36.550092 270)
			(size 1.8034 0.508)
			(layers "B.Cu" "B.Mask" "B.Paste")
			(net "M_F_DQ<31>")
		)
		(pad "189" smd rect
			(at -4.59994 37.399976 270)
			(size 1.8034 0.508)
			(layers "B.Cu" "B.Mask" "B.Paste")
			(net "GND")
		)
		(pad "190" smd rect
			(at -4.59994 38.250114 270)
			(size 1.8034 0.508)
			(layers "B.Cu" "B.Mask" "B.Paste")
			(net "M_F_DQ<27>")
		)
		(pad "191" smd rect
			(at -4.59994 39.099998 270)
			(size 1.8034 0.508)
			(layers "B.Cu" "B.Mask" "B.Paste")
			(net "GND")
		)
		(pad "192" smd rect
			(at -4.59994 39.949882 270)
			(size 1.8034 0.508)
			(layers "B.Cu" "B.Mask" "B.Paste")
			(net "M_F_ECC<5>")
		)
		(pad "193" smd rect
			(at -4.59994 40.80002 270)
			(size 1.8034 0.508)
			(layers "B.Cu" "B.Mask" "B.Paste")
			(net "GND")
		)
		(pad "194" smd rect
			(at -4.59994 41.649904 270)
			(size 1.8034 0.508)
			(layers "B.Cu" "B.Mask" "B.Paste")
			(net "M_F_ECC<1>")
		)
		(pad "195" smd rect
			(at -4.59994 42.500042 270)
			(size 1.8034 0.508)
			(layers "B.Cu" "B.Mask" "B.Paste")
			(net "GND")
		)
		(pad "196" smd rect
			(at -4.59994 43.349926 270)
			(size 1.8034 0.508)
			(layers "B.Cu" "B.Mask" "B.Paste")
			(net "M_F_DQS_DN<8>")
		)
		(pad "197" smd rect
			(at -4.59994 44.200064 270)
			(size 1.8034 0.508)
			(layers "B.Cu" "B.Mask" "B.Paste")
			(net "M_F_DQS_DP<8>")
		)
		(pad "198" smd rect
			(at -4.59994 45.049948 270)
			(size 1.8034 0.508)
			(layers "B.Cu" "B.Mask" "B.Paste")
			(net "GND")
		)
		(pad "199" smd rect
			(at -4.59994 45.900086 270)
			(size 1.8034 0.508)
			(layers "B.Cu" "B.Mask" "B.Paste")
			(net "M_F_ECC<7>")
		)
		(pad "200" smd rect
			(at -4.59994 46.74997 270)
			(size 1.8034 0.508)
			(layers "B.Cu" "B.Mask" "B.Paste")
			(net "GND")
		)
		(pad "201" smd rect
			(at -4.59994 47.600108 270)
			(size 1.8034 0.508)
			(layers "B.Cu" "B.Mask" "B.Paste")
			(net "M_F_ECC<3>")
		)
		(pad "202" smd rect
			(at -4.59994 48.449992 270)
			(size 1.8034 0.508)
			(layers "B.Cu" "B.Mask" "B.Paste")
			(net "GND")
		)
		(pad "203" smd rect
			(at -4.59994 49.299876 270)
			(size 1.8034 0.508)
			(layers "B.Cu" "B.Mask" "B.Paste")
			(net "M_F_CKE<3>")
		)
		(pad "204" smd rect
			(at -4.59994 50.150014 270)
			(size 1.8034 0.508)
			(layers "B.Cu" "B.Mask" "B.Paste")
			(net "PVDDQ_DEF")
		)
		(pad "205" smd rect
			(at -4.59994 50.999898 270)
			(size 1.8034 0.508)
			(layers "B.Cu" "B.Mask" "B.Paste")
			(net "TP_CH_F_DIMM_F1_RFU_0")
		)
		(pad "206" smd rect
			(at -4.59994 51.850036 270)
			(size 1.8034 0.508)
			(layers "B.Cu" "B.Mask" "B.Paste")
			(net "PVDDQ_DEF")
		)
		(pad "207" smd rect
			(at -4.59994 52.69992 270)
			(size 1.8034 0.508)
			(layers "B.Cu" "B.Mask" "B.Paste")
			(net "M_F_BG<1>")
		)
		(pad "208" smd rect
			(at -4.59994 53.550058 270)
			(size 1.8034 0.508)
			(layers "B.Cu" "B.Mask" "B.Paste")
			(net "M_F_ALERT_N")
		)
		(pad "209" smd rect
			(at -4.59994 54.399942 270)
			(size 1.8034 0.508)
			(layers "B.Cu" "B.Mask" "B.Paste")
			(net "PVDDQ_DEF")
		)
		(pad "210" smd rect
			(at -4.59994 55.25008 270)
			(size 1.8034 0.508)
			(layers "B.Cu" "B.Mask" "B.Paste")
			(net "M_F_MA<11>")
		)
		(pad "211" smd rect
			(at -4.59994 56.099964 270)
			(size 1.8034 0.508)
			(layers "B.Cu" "B.Mask" "B.Paste")
			(net "M_F_MA<7>")
		)
		(pad "212" smd rect
			(at -4.59994 56.950102 270)
			(size 1.8034 0.508)
			(layers "B.Cu" "B.Mask" "B.Paste")
			(net "PVDDQ_DEF")
		)
		(pad "213" smd rect
			(at -4.59994 57.799986 270)
			(size 1.8034 0.508)
			(layers "B.Cu" "B.Mask" "B.Paste")
			(net "M_F_MA<5>")
		)
		(pad "214" smd rect
			(at -4.59994 58.650124 270)
			(size 1.8034 0.508)
			(layers "B.Cu" "B.Mask" "B.Paste")
			(net "M_F_MA<4>")
		)
		(pad "215" smd rect
			(at -4.59994 59.500008 270)
			(size 1.8034 0.508)
			(layers "B.Cu" "B.Mask" "B.Paste")
			(net "PVDDQ_DEF")
		)
		(pad "216" smd rect
			(at -4.59994 60.349892 270)
			(size 1.8034 0.508)
			(layers "B.Cu" "B.Mask" "B.Paste")
			(net "M_F_MA<2>")
		)
		(pad "217" smd rect
			(at -4.59994 61.20003 270)
			(size 1.8034 0.508)
			(layers "B.Cu" "B.Mask" "B.Paste")
			(net "PVDDQ_DEF")
		)
		(pad "218" smd rect
			(at -4.59994 62.049914 270)
			(size 1.8034 0.508)
			(layers "B.Cu" "B.Mask" "B.Paste")
			(net "M_F_CLK_DP<3>")
		)
		(pad "219" smd rect
			(at -4.59994 62.900052 270)
			(size 1.8034 0.508)
			(layers "B.Cu" "B.Mask" "B.Paste")
			(net "M_F_CLK_DN<3>")
		)
		(pad "220" smd rect
			(at -4.59994 63.749936 270)
			(size 1.8034 0.508)
			(layers "B.Cu" "B.Mask" "B.Paste")
			(net "PVDDQ_DEF")
		)
		(pad "221" smd rect
			(at -4.59994 64.600074 270)
			(size 1.8034 0.508)
			(layers "B.Cu" "B.Mask" "B.Paste")
			(net "PVTT_DEF")
		)
		(pad "222" smd rect
			(at -4.59994 70.550024 270)
			(size 1.8034 0.508)
			(layers "B.Cu" "B.Mask" "B.Paste")
			(net "M_F_PAR")
		)
		(pad "223" smd rect
			(at -4.59994 71.399908 270)
			(size 1.8034 0.508)
			(layers "B.Cu" "B.Mask" "B.Paste")
			(net "PVDDQ_DEF")
		)
		(pad "224" smd rect
			(at -4.59994 72.250046 270)
			(size 1.8034 0.508)
			(layers "B.Cu" "B.Mask" "B.Paste")
			(net "M_F_BA<1>")
		)
		(pad "225" smd rect
			(at -4.59994 73.09993 270)
			(size 1.8034 0.508)
			(layers "B.Cu" "B.Mask" "B.Paste")
			(net "M_F_MA<10>")
		)
		(pad "226" smd rect
			(at -4.59994 73.950068 270)
			(size 1.8034 0.508)
			(layers "B.Cu" "B.Mask" "B.Paste")
			(net "PVDDQ_DEF")
		)
		(pad "227" smd rect
			(at -4.59994 74.799952 270)
			(size 1.8034 0.508)
			(layers "B.Cu" "B.Mask" "B.Paste")
			(net "TP_CH_F_DIMM_F1_RFU_1")
		)
		(pad "228" smd rect
			(at -4.59994 75.65009 270)
			(size 1.8034 0.508)
			(layers "B.Cu" "B.Mask" "B.Paste")
			(net "M_F_MA<14>")
		)
		(pad "229" smd rect
			(at -4.59994 76.499974 270)
			(size 1.8034 0.508)
			(layers "B.Cu" "B.Mask" "B.Paste")
			(net "PVDDQ_DEF")
		)
		(pad "230" smd rect
			(at -4.59994 77.350112 270)
			(size 1.8034 0.508)
			(layers "B.Cu" "B.Mask" "B.Paste")
			(net "FM_ADR_COMPLETE_DEF_N")
		)
		(pad "231" smd rect
			(at -4.59994 78.199996 270)
			(size 1.8034 0.508)
			(layers "B.Cu" "B.Mask" "B.Paste")
			(net "PVDDQ_DEF")
		)
		(pad "232" smd rect
			(at -4.59994 79.04988 270)
			(size 1.8034 0.508)
			(layers "B.Cu" "B.Mask" "B.Paste")
			(net "M_F_MA<13>")
		)
		(pad "233" smd rect
			(at -4.59994 79.900018 270)
			(size 1.8034 0.508)
			(layers "B.Cu" "B.Mask" "B.Paste")
			(net "PVDDQ_DEF")
		)
		(pad "234" smd rect
			(at -4.59994 80.749902 270)
			(size 1.8034 0.508)
			(layers "B.Cu" "B.Mask" "B.Paste")
			(net "M_F_MA<17>")
		)
		(pad "235" smd rect
			(at -4.59994 81.60004 270)
			(size 1.8034 0.508)
			(layers "B.Cu" "B.Mask" "B.Paste")
			(net "M_F_C<2>")
		)
		(pad "236" smd rect
			(at -4.59994 82.449924 270)
			(size 1.8034 0.508)
			(layers "B.Cu" "B.Mask" "B.Paste")
			(net "PVDDQ_DEF")
		)
		(pad "237" smd rect
			(at -4.59994 83.300062 270)
			(size 1.8034 0.508)
			(layers "B.Cu" "B.Mask" "B.Paste")
			(net "M_F_CS_N<7>")
		)
		(pad "238" smd rect
			(at -4.59994 84.149946 270)
			(size 1.8034 0.508)
			(layers "B.Cu" "B.Mask" "B.Paste")
			(net "PVPP_DEF")
		)
		(pad "239" smd rect
			(at -4.59994 85.000084 270)
			(size 1.8034 0.508)
			(layers "B.Cu" "B.Mask" "B.Paste")
			(net "GND")
		)
		(pad "240" smd rect
			(at -4.59994 85.849968 270)
			(size 1.8034 0.508)
			(layers "B.Cu" "B.Mask" "B.Paste")
			(net "M_F_DQ<37>")
		)
	)
)
